# T6G (Grand Teton) — schematic netlist excerpt (pin names and nets, part order shuffled) for the footprints in the layout excerpt that follows; sources: Cadence DE-HDL packaged netlist, KiCad conversion of 04192023_DAF0TMB3IC0_F0TG_MB_C_brd_V02_OCP.brd

R8016  Q_RES  0 5% EMPTY  pkg 0402LF  page 143 : A = OCP_V3_2_PRSNT23_R_N ; B = OCP_V3_2_PRSNT23_R1_N
D8004  SCHOTTKY_12  B0530WS7F EMPTY  pkg SOD323XB  page 92 : A = PWRGD_CHGL_CPU0_R1 ; C = P3V3_AUX

(kicad_pcb
	(version 20260206)
	(generator "pcbnew")
	(generator_version "10.0")
	(general
		(thickness 1.6)
		(legacy_teardrops no)
	)
	(paper "A4")
	(title_block
		(title "04192023_DAF0TMB3IC0_F0TG_MB_C_brd_V02_OCP.brd")
		(comment 1 "Grand Teton / footprints 4580-4581 of 8354")
	)
	(layers
		(0 "F.Cu" signal "TOP")
		(4 "In1.Cu" signal "GND")
		(6 "In2.Cu" signal "IN1")
		(8 "In3.Cu" signal "GND1")
		(10 "In4.Cu" signal "IN2")
		(12 "In5.Cu" signal "GND2")
		(14 "In6.Cu" signal "IN3")
		(16 "In7.Cu" signal "GND3")
		(18 "In8.Cu" signal "VCC")
		(20 "In9.Cu" signal "VCC1")
		(22 "In10.Cu" signal "GND4")
		(24 "In11.Cu" signal "IN4")
		(26 "In12.Cu" signal "GND5")
		(28 "In13.Cu" signal "IN5")
		(30 "In14.Cu" signal "GND6")
		(32 "In15.Cu" signal "IN6")
		(34 "In16.Cu" signal "GND7")
		(2 "B.Cu" signal "BOTTOM")
		(9 "F.Adhes" user "F.Adhesive")
		(11 "B.Adhes" user "B.Adhesive")
		(13 "F.Paste" user "Package Geometry/Pastemask Top")
		(15 "B.Paste" user "Package Geometry/Pastemask Bottom")
		(5 "F.SilkS" user "Ref Des/Silkscreen Top")
		(7 "B.SilkS" user "Ref Des/Silkscreen Bottom")
		(1 "F.Mask" user "Board Geometry/Soldermask Top")
		(3 "B.Mask" user "Board Geometry/Soldermask Bottom")
		(17 "Dwgs.User" user "User.Drawings")
		(19 "Cmts.User" user "User.Comments")
		(21 "Eco1.User" user "User.Eco1")
		(23 "Eco2.User" user "User.Eco2")
		(25 "Edge.Cuts" user "Board Geometry/Outline")
		(27 "Margin" user)
		(31 "F.CrtYd" user "Package Geometry/Place Bound Top")
		(29 "B.CrtYd" user "Package Geometry/Place Bound Bottom")
		(35 "F.Fab" user "Ref Des/Assembly Top")
		(33 "B.Fab" user "Ref Des/Assembly Bottom")
	)
	(footprint ""
		(layer "F.Cu")
		(at 11.557 -77.089)
		(property "Reference" "R8016"
			(at 0 0 0)
			(layer "F.SilkS")
			(hide yes)
			(effects
				(font
					(size 1.27 1.27)
				)
			)
		)
		(property "Value" ""
			(at 0 0 0)
			(layer "F.Fab")
			(effects
				(font
					(size 1.27 1.27)
				)
			)
		)
		(duplicate_pad_numbers_are_jumpers no)
		(fp_line
			(start -0.7874 -0.4064)
			(end 0.7874 -0.4064)
			(stroke
				(width 0.1524)
				(type default)
			)
			(layer "F.SilkS")
		)
		(fp_line
			(start -0.7874 0.4064)
			(end -0.7874 -0.4064)
			(stroke
				(width 0.1524)
				(type default)
			)
			(layer "F.SilkS")
		)
		(fp_line
			(start 0.7874 -0.4064)
			(end 0.7874 0.4064)
			(stroke
				(width 0.1524)
				(type default)
			)
			(layer "F.SilkS")
		)
		(fp_line
			(start 0.7874 0.4064)
			(end -0.7874 0.4064)
			(stroke
				(width 0.1524)
				(type default)
			)
			(layer "F.SilkS")
		)
		(fp_line
			(start -0.67945 -0.305054)
			(end -0.12065 -0.305054)
			(stroke
				(width 0.1)
				(type default)
			)
			(layer "F.Fab")
		)
		(fp_line
			(start -0.67945 0.3048)
			(end -0.67945 -0.305054)
			(stroke
				(width 0.1)
				(type default)
			)
			(layer "F.Fab")
		)
		(fp_line
			(start -0.12065 -0.305054)
			(end -0.12065 -0.2794)
			(stroke
				(width 0.1)
				(type default)
			)
			(layer "F.Fab")
		)
		(fp_line
			(start -0.12065 -0.2794)
			(end 0.12065 -0.2794)
			(stroke
				(width 0.1)
				(type default)
			)
			(layer "F.Fab")
		)
		(fp_line
			(start -0.12065 0.2794)
			(end -0.12065 0.3048)
			(stroke
				(width 0.1)
				(type default)
			)
			(layer "F.Fab")
		)
		(fp_line
			(start -0.12065 0.3048)
			(end -0.67945 0.3048)
			(stroke
				(width 0.1)
				(type default)
			)
			(layer "F.Fab")
		)
		(fp_line
			(start 0.120396 0.2794)
			(end -0.12065 0.2794)
			(stroke
				(width 0.1)
				(type default)
			)
			(layer "F.Fab")
		)
		(fp_line
			(start 0.120396 0.3048)
			(end 0.120396 0.2794)
			(stroke
				(width 0.1)
				(type default)
			)
			(layer "F.Fab")
		)
		(fp_line
			(start 0.12065 -0.3048)
			(end 0.67945 -0.3048)
			(stroke
				(width 0.1)
				(type default)
			)
			(layer "F.Fab")
		)
		(fp_line
			(start 0.12065 -0.2794)
			(end 0.12065 -0.3048)
			(stroke
				(width 0.1)
				(type default)
			)
			(layer "F.Fab")
		)
		(fp_line
			(start 0.67945 -0.3048)
			(end 0.67945 0.3048)
			(stroke
				(width 0.1)
				(type default)
			)
			(layer "F.Fab")
		)
		(fp_line
			(start 0.67945 0.3048)
			(end 0.120396 0.3048)
			(stroke
				(width 0.1)
				(type default)
			)
			(layer "F.Fab")
		)
		(pad "1" smd circle
			(at -0.40005 0)
			(size 0 0)
			(layers "F.Cu" "F.Mask" "F.Paste")
			(net "OCP_V3_2_PRSNT23_R_N")
		)
		(pad "2" smd circle
			(at 0.40005 0)
			(size 0 0)
			(layers "F.Cu" "F.Mask" "F.Paste")
			(net "OCP_V3_2_PRSNT23_R1_N")
		)
	)
	(footprint ""
		(layer "F.Cu")
		(at 204.851 -101.473)
		(property "Reference" "D8004"
			(at 3.037586 0.680466 0)
			(unlocked yes)
			(layer "F.SilkS")
			(effects
				(font
					(size 0.7874 0.5842)
					(thickness 0.1524)
				)
				(justify left)
			)
		)
		(property "Value" ""
			(at 0 0 0)
			(layer "F.Fab")
			(effects
				(font
					(size 1.27 1.27)
				)
			)
		)
		(duplicate_pad_numbers_are_jumpers no)
		(fp_line
			(start -2.050796 -0.700024)
			(end 2.050796 -0.700024)
			(stroke
				(width 0.1524)
				(type default)
			)
			(layer "F.SilkS")
		)
		(fp_line
			(start -2.050796 0.700024)
			(end -2.050796 -0.700024)
			(stroke
				(width 0.1524)
				(type default)
			)
			(layer "F.SilkS")
		)
		(fp_line
			(start -0.30607 -0.500126)
			(end -0.30607 0.500126)
			(stroke
				(width 0.1524)
				(type default)
			)
			(layer "F.SilkS")
		)
		(fp_line
			(start -0.30607 0.500126)
			(end 0.193802 0)
			(stroke
				(width 0.1524)
				(type default)
			)
			(layer "F.SilkS")
		)
		(fp_line
			(start 0.193802 0)
			(end -0.30607 -0.500126)
			(stroke
				(width 0.1524)
				(type default)
			)
			(layer "F.SilkS")
		)
		(fp_line
			(start 0.293878 -0.500126)
			(end 0.293878 0.500126)
			(stroke
				(width 0.1524)
				(type default)
			)
			(layer "F.SilkS")
		)
		(fp_line
			(start 2.050796 -0.700024)
			(end 2.050796 0.700024)
			(stroke
				(width 0.1524)
				(type default)
			)
			(layer "F.SilkS")
		)
		(fp_line
			(start 2.050796 0.700024)
			(end -2.050796 0.700024)
			(stroke
				(width 0.1524)
				(type default)
			)
			(layer "F.SilkS")
		)
		(fp_line
			(start 2.051304 0.635)
			(end 2.152904 0.635)
			(stroke
				(width 0.1524)
				(type default)
			)
			(layer "F.SilkS")
		)
		(fp_line
			(start 2.051304 0.6985)
			(end 2.051304 0.635)
			(stroke
				(width 0.1524)
				(type default)
			)
			(layer "F.SilkS")
		)
		(fp_line
			(start 2.064004 -0.6985)
			(end 2.229104 -0.6985)
			(stroke
				(width 0.1524)
				(type default)
			)
			(layer "F.SilkS")
		)
		(fp_line
			(start 2.064004 -0.6731)
			(end 2.064004 -0.6985)
			(stroke
				(width 0.1524)
				(type default)
			)
			(layer "F.SilkS")
		)
		(fp_line
			(start 2.152904 -0.6985)
			(end 2.343404 -0.6985)
			(stroke
				(width 0.1524)
				(type default)
			)
			(layer "F.SilkS")
		)
		(fp_line
			(start 2.152904 0.635)
			(end 2.152904 -0.6985)
			(stroke
				(width 0.1524)
				(type default)
			)
			(layer "F.SilkS")
		)
		(fp_line
			(start 2.229104 -0.6985)
			(end 2.229104 0.6985)
			(stroke
				(width 0.1524)
				(type default)
			)
			(layer "F.SilkS")
		)
		(fp_line
			(start 2.229104 0.6985)
			(end 2.051304 0.6985)
			(stroke
				(width 0.1524)
				(type default)
			)
			(layer "F.SilkS")
		)
		(fp_line
			(start 2.343404 -0.6985)
			(end 2.343404 0.6985)
			(stroke
				(width 0.1524)
				(type default)
			)
			(layer "F.SilkS")
		)
		(fp_line
			(start 2.343404 0.6985)
			(end 2.216404 0.6985)
			(stroke
				(width 0.1524)
				(type default)
			)
			(layer "F.SilkS")
		)
		(fp_line
			(start -0.899922 -0.700024)
			(end 0.899922 -0.700024)
			(stroke
				(width 0.1)
				(type default)
			)
			(layer "F.Fab")
		)
		(fp_line
			(start -0.899922 0.700024)
			(end -0.899922 -0.700024)
			(stroke
				(width 0.1)
				(type default)
			)
			(layer "F.Fab")
		)
		(fp_line
			(start 0.899922 -0.700024)
			(end 0.899922 0.700024)
			(stroke
				(width 0.1)
				(type default)
			)
			(layer "F.Fab")
		)
		(fp_line
			(start 0.899922 0.700024)
			(end -0.899922 0.700024)
			(stroke
				(width 0.1)
				(type default)
			)
			(layer "F.Fab")
		)
		(fp_text user "+"
			(at -2.772664 0.87757 90)
			(unlocked yes)
			(layer "F.SilkS")
			(effects
				(font
					(size 1.905 1.4224)
					(thickness 0.1524)
				)
				(justify left)
			)
		)
		(fp_text user "-"
			(at 3.880104 0.23495 180)
			(unlocked yes)
			(layer "F.SilkS")
			(effects
				(font
					(size 1.905 1.4224)
					(thickness 0.1524)
				)
				(justify left)
			)
		)
		(fp_text user "+"
			(at -3.123946 0.762 90)
			(unlocked yes)
			(layer "F.Fab")
			(effects
				(font
					(size 1.905 1.4224)
					(thickness 0.1524)
				)
				(justify left)
			)
		)
		(fp_text user "-"
			(at 3.880104 0.23495 180)
			(unlocked yes)
			(layer "F.Fab")
			(effects
				(font
					(size 1.905 1.4224)
					(thickness 0.1524)
				)
				(justify left)
			)
		)
		(pad "1" smd rect
			(at -1.199896 0 270)
			(size 0.6604 1.3716)
			(layers "F.Cu" "F.Mask" "F.Paste")
			(net "PWRGD_CHGL_CPU0_R1")
		)
		(pad "2" smd rect
			(at 1.199896 0 90)
			(size 0.6604 1.3716)
			(layers "F.Cu" "F.Mask" "F.Paste")
			(net "P3V3_AUX")
		)
	)
)
